(kicad_pcb
	(version 20260206)
	(generator "pcbnew")
	(generator_version "10.0")
	(general
		(thickness 1.6)
		(legacy_teardrops no)
	)
	(paper "A4")
	(title_block
		(title "03242023_DA0F0TMBIJ0_F0T_Motherboard_J_brd_V01_OCP.brd")
		(comment 1 "Grand Teton / footprint 1354 of 6105 (J30), pads 1-112 of 291")
	)
	(layers
		(0 "F.Cu" signal "TOP")
		(4 "In1.Cu" signal "GND")
		(6 "In2.Cu" signal "IN1")
		(8 "In3.Cu" signal "GND1")
		(10 "In4.Cu" signal "IN2")
		(12 "In5.Cu" signal "GND2")
		(14 "In6.Cu" signal "IN3")
		(16 "In7.Cu" signal "GND3")
		(18 "In8.Cu" signal "VCC")
		(20 "In9.Cu" signal "VCC1")
		(22 "In10.Cu" signal "GND4")
		(24 "In11.Cu" signal "IN4")
		(26 "In12.Cu" signal "GND5")
		(28 "In13.Cu" signal "IN5")
		(30 "In14.Cu" signal "GND6")
		(32 "In15.Cu" signal "IN6")
		(34 "In16.Cu" signal "GND7")
		(2 "B.Cu" signal "BOTTOM")
		(9 "F.Adhes" user "F.Adhesive")
		(11 "B.Adhes" user "B.Adhesive")
		(13 "F.Paste" user "Package Geometry/Pastemask Top")
		(15 "B.Paste" user "Package Geometry/Pastemask Bottom")
		(5 "F.SilkS" user "Ref Des/Silkscreen Top")
		(7 "B.SilkS" user "Ref Des/Silkscreen Bottom")
		(1 "F.Mask" user "Board Geometry/Soldermask Top")
		(3 "B.Mask" user "Board Geometry/Soldermask Bottom")
		(17 "Dwgs.User" user "User.Drawings")
		(19 "Cmts.User" user "User.Comments")
		(21 "Eco1.User" user "User.Eco1")
		(23 "Eco2.User" user "User.Eco2")
		(25 "Edge.Cuts" user "Board Geometry/Outline")
		(27 "Margin" user)
		(31 "F.CrtYd" user "Package Geometry/Place Bound Top")
		(29 "B.CrtYd" user "Package Geometry/Place Bound Bottom")
		(35 "F.Fab" user "Ref Des/Assembly Top")
		(33 "B.Fab" user "Ref Des/Assembly Bottom")
	)
	(footprint ""
		(layer "F.Cu")
		(at 191.03848 -258.091686)
		(property "Reference" "J30"
			(at -2.98196 -81.740248 0)
			(unlocked yes)
			(layer "F.SilkS")
			(effects
				(font
					(size 0.7874 0.5842)
					(thickness 0.1524)
				)
				(justify left)
			)
		)
		(property "Value" ""
			(at 0 0 0)
			(layer "F.Fab")
			(effects
				(font
					(size 1.27 1.27)
				)
			)
		)
		(duplicate_pad_numbers_are_jumpers no)
		(pad "1" smd rect
			(at -2.050034 -63.324994 270)
			(size 0.519938 1.4986)
			(layers "F.Cu" "F.Mask" "F.Paste")
			(net "P12V_S3_AUX_CPU1_NVDIMM")
		)
		(pad "2" smd rect
			(at -2.050034 -62.47511 270)
			(size 0.519938 1.4986)
			(layers "F.Cu" "F.Mask" "F.Paste")
			(net "TP_CHG_CPU1_DIMM2_FRU_0")
		)
		(pad "3" smd rect
			(at -2.050034 -61.624972 270)
			(size 0.519938 1.4986)
			(layers "F.Cu" "F.Mask" "F.Paste")
			(net "P3V3_AUX")
		)
		(pad "4" smd rect
			(at -2.050034 -60.775088 270)
			(size 0.519938 1.4986)
			(layers "F.Cu" "F.Mask" "F.Paste")
			(net "I3C_SPD_DDREFGH_CPU1_LVC1_SCL_5")
		)
		(pad "5" smd rect
			(at -2.050034 -59.92495 270)
			(size 0.519938 1.4986)
			(layers "F.Cu" "F.Mask" "F.Paste")
			(net "I3C_SPD_DDREFGH_CPU1_LVC1_SDA")
		)
		(pad "6" smd rect
			(at -2.050034 -59.075066 270)
			(size 0.519938 1.4986)
			(layers "F.Cu" "F.Mask" "F.Paste")
			(net "GND")
		)
		(pad "7" smd rect
			(at -2.050034 -58.224928 270)
			(size 0.519938 1.4986)
			(layers "F.Cu" "F.Mask" "F.Paste")
			(net "M_G_CPU1_SA_DQ<0>")
		)
		(pad "8" smd rect
			(at -2.050034 -57.375044 270)
			(size 0.519938 1.4986)
			(layers "F.Cu" "F.Mask" "F.Paste")
			(net "GND")
		)
		(pad "9" smd rect
			(at -2.050034 -56.524906 270)
			(size 0.519938 1.4986)
			(layers "F.Cu" "F.Mask" "F.Paste")
			(net "M_G_CPU1_SA_DQ<1>")
		)
		(pad "10" smd rect
			(at -2.050034 -55.675022 270)
			(size 0.519938 1.4986)
			(layers "F.Cu" "F.Mask" "F.Paste")
			(net "GND")
		)
		(pad "11" smd rect
			(at -2.050034 -54.824884 270)
			(size 0.519938 1.4986)
			(layers "F.Cu" "F.Mask" "F.Paste")
			(net "M_G_CPU1_SA_DQS_DP<0>")
		)
		(pad "12" smd rect
			(at -2.050034 -53.975 270)
			(size 0.519938 1.4986)
			(layers "F.Cu" "F.Mask" "F.Paste")
			(net "M_G_CPU1_SA_DQS_DN<0>")
		)
		(pad "13" smd rect
			(at -2.050034 -53.125116 270)
			(size 0.519938 1.4986)
			(layers "F.Cu" "F.Mask" "F.Paste")
			(net "GND")
		)
		(pad "14" smd rect
			(at -2.050034 -52.274978 270)
			(size 0.519938 1.4986)
			(layers "F.Cu" "F.Mask" "F.Paste")
			(net "M_G_CPU1_SA_DQ<4>")
		)
		(pad "15" smd rect
			(at -2.050034 -51.425094 270)
			(size 0.519938 1.4986)
			(layers "F.Cu" "F.Mask" "F.Paste")
			(net "GND")
		)
		(pad "16" smd rect
			(at -2.050034 -50.574956 270)
			(size 0.519938 1.4986)
			(layers "F.Cu" "F.Mask" "F.Paste")
			(net "M_G_CPU1_SA_DQ<5>")
		)
		(pad "17" smd rect
			(at -2.050034 -49.725072 270)
			(size 0.519938 1.4986)
			(layers "F.Cu" "F.Mask" "F.Paste")
			(net "GND")
		)
		(pad "18" smd rect
			(at -2.050034 -48.874934 270)
			(size 0.519938 1.4986)
			(layers "F.Cu" "F.Mask" "F.Paste")
			(net "M_G_CPU1_SA_DQ<8>")
		)
		(pad "19" smd rect
			(at -2.050034 -48.02505 270)
			(size 0.519938 1.4986)
			(layers "F.Cu" "F.Mask" "F.Paste")
			(net "GND")
		)
		(pad "20" smd rect
			(at -2.050034 -47.174912 270)
			(size 0.519938 1.4986)
			(layers "F.Cu" "F.Mask" "F.Paste")
			(net "M_G_CPU1_SA_DQ<9>")
		)
		(pad "21" smd rect
			(at -2.050034 -46.325028 270)
			(size 0.519938 1.4986)
			(layers "F.Cu" "F.Mask" "F.Paste")
			(net "GND")
		)
		(pad "22" smd rect
			(at -2.050034 -45.47489 270)
			(size 0.519938 1.4986)
			(layers "F.Cu" "F.Mask" "F.Paste")
			(net "M_G_CPU1_SA_DQS_DP<1>")
		)
		(pad "23" smd rect
			(at -2.050034 -44.625006 270)
			(size 0.519938 1.4986)
			(layers "F.Cu" "F.Mask" "F.Paste")
			(net "M_G_CPU1_SA_DQS_DN<1>")
		)
		(pad "24" smd rect
			(at -2.050034 -43.775122 270)
			(size 0.519938 1.4986)
			(layers "F.Cu" "F.Mask" "F.Paste")
			(net "GND")
		)
		(pad "25" smd rect
			(at -2.050034 -42.924984 270)
			(size 0.519938 1.4986)
			(layers "F.Cu" "F.Mask" "F.Paste")
			(net "M_G_CPU1_SA_DQ<12>")
		)
		(pad "26" smd rect
			(at -2.050034 -42.0751 270)
			(size 0.519938 1.4986)
			(layers "F.Cu" "F.Mask" "F.Paste")
			(net "GND")
		)
		(pad "27" smd rect
			(at -2.050034 -41.224962 270)
			(size 0.519938 1.4986)
			(layers "F.Cu" "F.Mask" "F.Paste")
			(net "M_G_CPU1_SA_DQ<13>")
		)
		(pad "28" smd rect
			(at -2.050034 -40.375078 270)
			(size 0.519938 1.4986)
			(layers "F.Cu" "F.Mask" "F.Paste")
			(net "GND")
		)
		(pad "29" smd rect
			(at -2.050034 -39.52494 270)
			(size 0.519938 1.4986)
			(layers "F.Cu" "F.Mask" "F.Paste")
			(net "M_G_CPU1_SA_DQ<16>")
		)
		(pad "30" smd rect
			(at -2.050034 -38.675056 270)
			(size 0.519938 1.4986)
			(layers "F.Cu" "F.Mask" "F.Paste")
			(net "GND")
		)
		(pad "31" smd rect
			(at -2.050034 -37.824918 270)
			(size 0.519938 1.4986)
			(layers "F.Cu" "F.Mask" "F.Paste")
			(net "M_G_CPU1_SA_DQ<17>")
		)
		(pad "32" smd rect
			(at -2.050034 -36.975034 270)
			(size 0.519938 1.4986)
			(layers "F.Cu" "F.Mask" "F.Paste")
			(net "GND")
		)
		(pad "33" smd rect
			(at -2.050034 -36.124896 270)
			(size 0.519938 1.4986)
			(layers "F.Cu" "F.Mask" "F.Paste")
			(net "M_G_CPU1_SA_DQS_DP<2>")
		)
		(pad "34" smd rect
			(at -2.050034 -35.275012 270)
			(size 0.519938 1.4986)
			(layers "F.Cu" "F.Mask" "F.Paste")
			(net "M_G_CPU1_SA_DQS_DN<2>")
		)
		(pad "35" smd rect
			(at -2.050034 -34.425128 270)
			(size 0.519938 1.4986)
			(layers "F.Cu" "F.Mask" "F.Paste")
			(net "GND")
		)
		(pad "36" smd rect
			(at -2.050034 -33.57499 270)
			(size 0.519938 1.4986)
			(layers "F.Cu" "F.Mask" "F.Paste")
			(net "M_G_CPU1_SA_DQ<20>")
		)
		(pad "37" smd rect
			(at -2.050034 -32.725106 270)
			(size 0.519938 1.4986)
			(layers "F.Cu" "F.Mask" "F.Paste")
			(net "GND")
		)
		(pad "38" smd rect
			(at -2.050034 -31.874968 270)
			(size 0.519938 1.4986)
			(layers "F.Cu" "F.Mask" "F.Paste")
			(net "M_G_CPU1_SA_DQ<21>")
		)
		(pad "39" smd rect
			(at -2.050034 -31.025084 270)
			(size 0.519938 1.4986)
			(layers "F.Cu" "F.Mask" "F.Paste")
			(net "GND")
		)
		(pad "40" smd rect
			(at -2.050034 -30.174946 270)
			(size 0.519938 1.4986)
			(layers "F.Cu" "F.Mask" "F.Paste")
			(net "M_G_CPU1_SA_DQ<24>")
		)
		(pad "41" smd rect
			(at -2.050034 -29.325062 270)
			(size 0.519938 1.4986)
			(layers "F.Cu" "F.Mask" "F.Paste")
			(net "GND")
		)
		(pad "42" smd rect
			(at -2.050034 -28.474924 270)
			(size 0.519938 1.4986)
			(layers "F.Cu" "F.Mask" "F.Paste")
			(net "M_G_CPU1_SA_DQ<25>")
		)
		(pad "43" smd rect
			(at -2.050034 -27.62504 270)
			(size 0.519938 1.4986)
			(layers "F.Cu" "F.Mask" "F.Paste")
			(net "GND")
		)
		(pad "44" smd rect
			(at -2.050034 -26.774902 270)
			(size 0.519938 1.4986)
			(layers "F.Cu" "F.Mask" "F.Paste")
			(net "M_G_CPU1_SA_DQS_DP<3>")
		)
		(pad "45" smd rect
			(at -2.050034 -25.925018 270)
			(size 0.519938 1.4986)
			(layers "F.Cu" "F.Mask" "F.Paste")
			(net "M_G_CPU1_SA_DQS_DN<3>")
		)
		(pad "46" smd rect
			(at -2.050034 -25.07488 270)
			(size 0.519938 1.4986)
			(layers "F.Cu" "F.Mask" "F.Paste")
			(net "GND")
		)
		(pad "47" smd rect
			(at -2.050034 -24.224996 270)
			(size 0.519938 1.4986)
			(layers "F.Cu" "F.Mask" "F.Paste")
			(net "M_G_CPU1_SA_DQ<28>")
		)
		(pad "48" smd rect
			(at -2.050034 -23.375112 270)
			(size 0.519938 1.4986)
			(layers "F.Cu" "F.Mask" "F.Paste")
			(net "GND")
		)
		(pad "49" smd rect
			(at -2.050034 -22.524974 270)
			(size 0.519938 1.4986)
			(layers "F.Cu" "F.Mask" "F.Paste")
			(net "M_G_CPU1_SA_DQ<29>")
		)
		(pad "50" smd rect
			(at -2.050034 -21.67509 270)
			(size 0.519938 1.4986)
			(layers "F.Cu" "F.Mask" "F.Paste")
			(net "GND")
		)
		(pad "51" smd rect
			(at -2.050034 -20.824952 270)
			(size 0.519938 1.4986)
			(layers "F.Cu" "F.Mask" "F.Paste")
			(net "M_G_CPU1_SA_CB<0>")
		)
		(pad "52" smd rect
			(at -2.050034 -19.975068 270)
			(size 0.519938 1.4986)
			(layers "F.Cu" "F.Mask" "F.Paste")
			(net "GND")
		)
		(pad "53" smd rect
			(at -2.050034 -19.12493 270)
			(size 0.519938 1.4986)
			(layers "F.Cu" "F.Mask" "F.Paste")
			(net "M_G_CPU1_SA_CB<1>")
		)
		(pad "54" smd rect
			(at -2.050034 -18.275046 270)
			(size 0.519938 1.4986)
			(layers "F.Cu" "F.Mask" "F.Paste")
			(net "GND")
		)
		(pad "55" smd rect
			(at -2.050034 -17.424908 270)
			(size 0.519938 1.4986)
			(layers "F.Cu" "F.Mask" "F.Paste")
			(net "M_G_CPU1_SA_DQS_DP<4>")
		)
		(pad "56" smd rect
			(at -2.050034 -16.575024 270)
			(size 0.519938 1.4986)
			(layers "F.Cu" "F.Mask" "F.Paste")
			(net "M_G_CPU1_SA_DQS_DN<4>")
		)
		(pad "57" smd rect
			(at -2.050034 -15.724886 270)
			(size 0.519938 1.4986)
			(layers "F.Cu" "F.Mask" "F.Paste")
			(net "GND")
		)
		(pad "58" smd rect
			(at -2.050034 -14.875002 270)
			(size 0.519938 1.4986)
			(layers "F.Cu" "F.Mask" "F.Paste")
			(net "M_G_CPU1_SA_CB<4>")
		)
		(pad "59" smd rect
			(at -2.050034 -14.025118 270)
			(size 0.519938 1.4986)
			(layers "F.Cu" "F.Mask" "F.Paste")
			(net "GND")
		)
		(pad "60" smd rect
			(at -2.050034 -13.17498 270)
			(size 0.519938 1.4986)
			(layers "F.Cu" "F.Mask" "F.Paste")
			(net "M_G_CPU1_SA_CB<5>")
		)
		(pad "61" smd rect
			(at -2.050034 -12.325096 270)
			(size 0.519938 1.4986)
			(layers "F.Cu" "F.Mask" "F.Paste")
			(net "GND")
		)
		(pad "62" smd rect
			(at -2.050034 -11.474958 270)
			(size 0.519938 1.4986)
			(layers "F.Cu" "F.Mask" "F.Paste")
			(net "M_G_CPU1_ALERT_N")
		)
		(pad "63" smd rect
			(at -2.050034 -10.625074 270)
			(size 0.519938 1.4986)
			(layers "F.Cu" "F.Mask" "F.Paste")
			(net "GND")
		)
		(pad "64" smd rect
			(at -2.050034 -9.774936 270)
			(size 0.519938 1.4986)
			(layers "F.Cu" "F.Mask" "F.Paste")
			(net "M_G_CPU1_SA_CS_N<2>")
		)
		(pad "65" smd rect
			(at -2.050034 -8.925052 270)
			(size 0.519938 1.4986)
			(layers "F.Cu" "F.Mask" "F.Paste")
			(net "GND")
		)
		(pad "66" smd rect
			(at -2.050034 -8.074914 270)
			(size 0.519938 1.4986)
			(layers "F.Cu" "F.Mask" "F.Paste")
			(net "M_G_CPU1_SA_CA<0>")
		)
		(pad "67" smd rect
			(at -2.050034 -7.22503 270)
			(size 0.519938 1.4986)
			(layers "F.Cu" "F.Mask" "F.Paste")
			(net "GND")
		)
		(pad "68" smd rect
			(at -2.050034 -6.374892 270)
			(size 0.519938 1.4986)
			(layers "F.Cu" "F.Mask" "F.Paste")
			(net "M_G_CPU1_SA_CA<2>")
		)
		(pad "69" smd rect
			(at -2.050034 -5.525008 270)
			(size 0.519938 1.4986)
			(layers "F.Cu" "F.Mask" "F.Paste")
			(net "GND")
		)
		(pad "70" smd rect
			(at -2.050034 -4.675124 270)
			(size 0.519938 1.4986)
			(layers "F.Cu" "F.Mask" "F.Paste")
			(net "M_G_CPU1_SA_CA<4>")
		)
		(pad "71" smd rect
			(at -2.050034 -3.824986 270)
			(size 0.519938 1.4986)
			(layers "F.Cu" "F.Mask" "F.Paste")
			(net "GND")
		)
		(pad "72" smd rect
			(at -2.050034 -2.975102 270)
			(size 0.519938 1.4986)
			(layers "F.Cu" "F.Mask" "F.Paste")
			(net "M_G_CPU1_SA_CA<6>")
		)
		(pad "73" smd rect
			(at -2.050034 -2.124964 270)
			(size 0.519938 1.4986)
			(layers "F.Cu" "F.Mask" "F.Paste")
			(net "GND")
		)
		(pad "74" smd rect
			(at -2.050034 -1.27508 270)
			(size 0.519938 1.4986)
			(layers "F.Cu" "F.Mask" "F.Paste")
			(net "M_G_CPU1_SA_PAR")
		)
		(pad "75" smd rect
			(at -2.050034 -0.424942 270)
			(size 0.519938 1.4986)
			(layers "F.Cu" "F.Mask" "F.Paste")
			(net "GND")
		)
		(pad "76" smd rect
			(at -2.050034 5.525008 270)
			(size 0.519938 1.4986)
			(layers "F.Cu" "F.Mask" "F.Paste")
			(net "M_G_CPU1_SB_CA<0>")
		)
		(pad "77" smd rect
			(at -2.050034 6.374892 270)
			(size 0.519938 1.4986)
			(layers "F.Cu" "F.Mask" "F.Paste")
			(net "GND")
		)
		(pad "78" smd rect
			(at -2.050034 7.22503 270)
			(size 0.519938 1.4986)
			(layers "F.Cu" "F.Mask" "F.Paste")
			(net "M_G_CPU1_SB_CA<2>")
		)
		(pad "79" smd rect
			(at -2.050034 8.074914 270)
			(size 0.519938 1.4986)
			(layers "F.Cu" "F.Mask" "F.Paste")
			(net "GND")
		)
		(pad "80" smd rect
			(at -2.050034 8.925052 270)
			(size 0.519938 1.4986)
			(layers "F.Cu" "F.Mask" "F.Paste")
			(net "M_G_CPU1_SB_CA<4>")
		)
		(pad "81" smd rect
			(at -2.050034 9.774936 270)
			(size 0.519938 1.4986)
			(layers "F.Cu" "F.Mask" "F.Paste")
			(net "GND")
		)
		(pad "82" smd rect
			(at -2.050034 10.625074 270)
			(size 0.519938 1.4986)
			(layers "F.Cu" "F.Mask" "F.Paste")
			(net "M_G_CPU1_SB_CA<6>")
		)
		(pad "83" smd rect
			(at -2.050034 11.474958 270)
			(size 0.519938 1.4986)
			(layers "F.Cu" "F.Mask" "F.Paste")
			(net "GND")
		)
		(pad "84" smd rect
			(at -2.050034 12.325096 270)
			(size 0.519938 1.4986)
			(layers "F.Cu" "F.Mask" "F.Paste")
			(net "M_G_CPU1_SB_CS_N<2>")
		)
		(pad "85" smd rect
			(at -2.050034 13.17498 270)
			(size 0.519938 1.4986)
			(layers "F.Cu" "F.Mask" "F.Paste")
			(net "GND")
		)
		(pad "86" smd rect
			(at -2.050034 14.025118 270)
			(size 0.519938 1.4986)
			(layers "F.Cu" "F.Mask" "F.Paste")
			(net "M_G_CPU1_SA_RSP<1>")
		)
		(pad "87" smd rect
			(at -2.050034 14.875002 270)
			(size 0.519938 1.4986)
			(layers "F.Cu" "F.Mask" "F.Paste")
			(net "M_G_CPU1_SB_RSP<1>")
		)
		(pad "88" smd rect
			(at -2.050034 15.724886 270)
			(size 0.519938 1.4986)
			(layers "F.Cu" "F.Mask" "F.Paste")
			(net "GND")
		)
		(pad "89" smd rect
			(at -2.050034 16.575024 270)
			(size 0.519938 1.4986)
			(layers "F.Cu" "F.Mask" "F.Paste")
			(net "M_G_CPU1_SB_CB<4>")
		)
		(pad "90" smd rect
			(at -2.050034 17.424908 270)
			(size 0.519938 1.4986)
			(layers "F.Cu" "F.Mask" "F.Paste")
			(net "GND")
		)
		(pad "91" smd rect
			(at -2.050034 18.275046 270)
			(size 0.519938 1.4986)
			(layers "F.Cu" "F.Mask" "F.Paste")
			(net "M_G_CPU1_SB_CB<5>")
		)
		(pad "92" smd rect
			(at -2.050034 19.12493 270)
			(size 0.519938 1.4986)
			(layers "F.Cu" "F.Mask" "F.Paste")
			(net "GND")
		)
		(pad "93" smd rect
			(at -2.050034 19.975068 270)
			(size 0.519938 1.4986)
			(layers "F.Cu" "F.Mask" "F.Paste")
			(net "M_G_CPU1_SB_DQS_DP<9>")
		)
		(pad "94" smd rect
			(at -2.050034 20.824952 270)
			(size 0.519938 1.4986)
			(layers "F.Cu" "F.Mask" "F.Paste")
			(net "M_G_CPU1_SB_DQS_DN<9>")
		)
		(pad "95" smd rect
			(at -2.050034 21.67509 270)
			(size 0.519938 1.4986)
			(layers "F.Cu" "F.Mask" "F.Paste")
			(net "GND")
		)
		(pad "96" smd rect
			(at -2.050034 22.524974 270)
			(size 0.519938 1.4986)
			(layers "F.Cu" "F.Mask" "F.Paste")
			(net "M_G_CPU1_SB_CB<0>")
		)
		(pad "97" smd rect
			(at -2.050034 23.375112 270)
			(size 0.519938 1.4986)
			(layers "F.Cu" "F.Mask" "F.Paste")
			(net "GND")
		)
		(pad "98" smd rect
			(at -2.050034 24.224996 270)
			(size 0.519938 1.4986)
			(layers "F.Cu" "F.Mask" "F.Paste")
			(net "M_G_CPU1_SB_CB<1>")
		)
		(pad "99" smd rect
			(at -2.050034 25.07488 270)
			(size 0.519938 1.4986)
			(layers "F.Cu" "F.Mask" "F.Paste")
			(net "GND")
		)
		(pad "100" smd rect
			(at -2.050034 25.925018 270)
			(size 0.519938 1.4986)
			(layers "F.Cu" "F.Mask" "F.Paste")
			(net "M_G_CPU1_SB_DQ<0>")
		)
		(pad "101" smd rect
			(at -2.050034 26.774902 270)
			(size 0.519938 1.4986)
			(layers "F.Cu" "F.Mask" "F.Paste")
			(net "GND")
		)
		(pad "102" smd rect
			(at -2.050034 27.62504 270)
			(size 0.519938 1.4986)
			(layers "F.Cu" "F.Mask" "F.Paste")
			(net "M_G_CPU1_SB_DQ<1>")
		)
		(pad "103" smd rect
			(at -2.050034 28.474924 270)
			(size 0.519938 1.4986)
			(layers "F.Cu" "F.Mask" "F.Paste")
			(net "GND")
		)
		(pad "104" smd rect
			(at -2.050034 29.325062 270)
			(size 0.519938 1.4986)
			(layers "F.Cu" "F.Mask" "F.Paste")
			(net "M_G_CPU1_SB_DQS_DP<0>")
		)
		(pad "105" smd rect
			(at -2.050034 30.174946 270)
			(size 0.519938 1.4986)
			(layers "F.Cu" "F.Mask" "F.Paste")
			(net "M_G_CPU1_SB_DQS_DN<0>")
		)
		(pad "106" smd rect
			(at -2.050034 31.025084 270)
			(size 0.519938 1.4986)
			(layers "F.Cu" "F.Mask" "F.Paste")
			(net "GND")
		)
		(pad "107" smd rect
			(at -2.050034 31.874968 270)
			(size 0.519938 1.4986)
			(layers "F.Cu" "F.Mask" "F.Paste")
			(net "M_G_CPU1_SB_DQ<4>")
		)
		(pad "108" smd rect
			(at -2.050034 32.725106 270)
			(size 0.519938 1.4986)
			(layers "F.Cu" "F.Mask" "F.Paste")
			(net "GND")
		)
		(pad "109" smd rect
			(at -2.050034 33.57499 270)
			(size 0.519938 1.4986)
			(layers "F.Cu" "F.Mask" "F.Paste")
			(net "M_G_CPU1_SB_DQ<5>")
		)
		(pad "110" smd rect
			(at -2.050034 34.425128 270)
			(size 0.519938 1.4986)
			(layers "F.Cu" "F.Mask" "F.Paste")
			(net "GND")
		)
		(pad "111" smd rect
			(at -2.050034 35.275012 270)
			(size 0.519938 1.4986)
			(layers "F.Cu" "F.Mask" "F.Paste")
			(net "M_G_CPU1_SB_DQ<8>")
		)
		(pad "112" smd rect
			(at -2.050034 36.124896 270)
			(size 0.519938 1.4986)
			(layers "F.Cu" "F.Mask" "F.Paste")
			(net "GND")
		)
	)
)
